# T6G (Grand Teton) — schematic netlist excerpt (pin names and nets, part order shuffled) for the footprints in the layout excerpt that follows; sources: Cadence DE-HDL packaged netlist, KiCad conversion of 04192023_DAF0TMB3IC0_F0TG_MB_C_brd_V02_OCP.brd

PR6607  Q_RES  1K 1% EMPTY  pkg 0402LF  page 362 : A = P0V9_RETIMER_CPU0_VINSEN ; B = GND

U195  74LVC2G17GW  IC  pkg SOT363  page 130
  A0  = BMC_MONITER_R
  GND  = GND
  A1  = RST_SWB_BIC_R_N
  B1  = RST_SWB_BIC_BUF_R_N
  VCC  = P3V3_AUX
  B0  = BMC_MONITER_BUF_R

(kicad_pcb
	(version 20260206)
	(generator "pcbnew")
	(generator_version "10.0")
	(general
		(thickness 1.6)
		(legacy_teardrops no)
	)
	(paper "A4")
	(title_block
		(title "04192023_DAF0TMB3IC0_F0TG_MB_C_brd_V02_OCP.brd")
		(comment 1 "Grand Teton / footprints 4952-4953 of 8354")
	)
	(layers
		(0 "F.Cu" signal "TOP")
		(4 "In1.Cu" signal "GND")
		(6 "In2.Cu" signal "IN1")
		(8 "In3.Cu" signal "GND1")
		(10 "In4.Cu" signal "IN2")
		(12 "In5.Cu" signal "GND2")
		(14 "In6.Cu" signal "IN3")
		(16 "In7.Cu" signal "GND3")
		(18 "In8.Cu" signal "VCC")
		(20 "In9.Cu" signal "VCC1")
		(22 "In10.Cu" signal "GND4")
		(24 "In11.Cu" signal "IN4")
		(26 "In12.Cu" signal "GND5")
		(28 "In13.Cu" signal "IN5")
		(30 "In14.Cu" signal "GND6")
		(32 "In15.Cu" signal "IN6")
		(34 "In16.Cu" signal "GND7")
		(2 "B.Cu" signal "BOTTOM")
		(9 "F.Adhes" user "F.Adhesive")
		(11 "B.Adhes" user "B.Adhesive")
		(13 "F.Paste" user "Package Geometry/Pastemask Top")
		(15 "B.Paste" user "Package Geometry/Pastemask Bottom")
		(5 "F.SilkS" user "Ref Des/Silkscreen Top")
		(7 "B.SilkS" user "Ref Des/Silkscreen Bottom")
		(1 "F.Mask" user "Board Geometry/Soldermask Top")
		(3 "B.Mask" user "Board Geometry/Soldermask Bottom")
		(17 "Dwgs.User" user "User.Drawings")
		(19 "Cmts.User" user "User.Comments")
		(21 "Eco1.User" user "User.Eco1")
		(23 "Eco2.User" user "User.Eco2")
		(25 "Edge.Cuts" user "Board Geometry/Outline")
		(27 "Margin" user)
		(31 "F.CrtYd" user "Package Geometry/Place Bound Top")
		(29 "B.CrtYd" user "Package Geometry/Place Bound Bottom")
		(35 "F.Fab" user "Ref Des/Assembly Top")
		(33 "B.Fab" user "Ref Des/Assembly Bottom")
	)
	(footprint ""
		(layer "B.Cu")
		(at 176.432972 -414.435544 180)
		(property "Reference" "U195"
			(at -2.873502 -2.892298 0)
			(unlocked yes)
			(layer "B.SilkS")
			(effects
				(font
					(size 0.7874 0.5842)
					(thickness 0.1524)
				)
				(justify left mirror)
			)
		)
		(property "Value" ""
			(at 0 0 0)
			(layer "B.Fab")
			(effects
				(font
					(size 1.27 1.27)
				)
				(justify mirror)
			)
		)
		(duplicate_pad_numbers_are_jumpers no)
		(fp_line
			(start 1.3462 1.100074)
			(end 1.3462 -1.100074)
			(stroke
				(width 0.1524)
				(type default)
			)
			(layer "B.SilkS")
		)
		(fp_line
			(start 1.3462 -1.100074)
			(end 0.670052 -1.100074)
			(stroke
				(width 0.1524)
				(type default)
			)
			(layer "B.SilkS")
		)
		(fp_line
			(start 0.670052 -1.100074)
			(end 0 -0.381)
			(stroke
				(width 0.1524)
				(type default)
			)
			(layer "B.SilkS")
		)
		(fp_line
			(start 0 -0.381)
			(end -0.670052 -1.100074)
			(stroke
				(width 0.1524)
				(type default)
			)
			(layer "B.SilkS")
		)
		(fp_line
			(start -0.670052 -1.100074)
			(end -1.3462 -1.100074)
			(stroke
				(width 0.1524)
				(type default)
			)
			(layer "B.SilkS")
		)
		(fp_line
			(start -1.3462 1.100074)
			(end 1.3462 1.100074)
			(stroke
				(width 0.1524)
				(type default)
			)
			(layer "B.SilkS")
		)
		(fp_line
			(start -1.3462 -1.100074)
			(end -1.3462 1.100074)
			(stroke
				(width 0.1524)
				(type default)
			)
			(layer "B.SilkS")
		)
		(fp_poly
			(pts
				(xy 3.007868 -0.33909) (xy 2.990088 -1.100836) (xy 2.237232 -0.702056)
			)
			(stroke
				(width 0)
				(type default)
			)
			(fill yes)
			(layer "B.SilkS")
		)
		(fp_line
			(start 1.100074 0.8001)
			(end 1.100074 -0.8001)
			(stroke
				(width 0.1)
				(type default)
			)
			(layer "B.Fab")
		)
		(fp_line
			(start 1.100074 -0.8001)
			(end 0.670052 -0.8001)
			(stroke
				(width 0.1)
				(type default)
			)
			(layer "B.Fab")
		)
		(fp_line
			(start 0.670052 1.100074)
			(end 0.670052 0.8001)
			(stroke
				(width 0.1)
				(type default)
			)
			(layer "B.Fab")
		)
		(fp_line
			(start 0.670052 0.8001)
			(end 1.100074 0.8001)
			(stroke
				(width 0.1)
				(type default)
			)
			(layer "B.Fab")
		)
		(fp_line
			(start 0.670052 0.8001)
			(end 0.670052 -0.8001)
			(stroke
				(width 0.1)
				(type default)
			)
			(layer "B.Fab")
		)
		(fp_line
			(start 0.670052 -0.8001)
			(end 0.670052 -1.100074)
			(stroke
				(width 0.1)
				(type default)
			)
			(layer "B.Fab")
		)
		(fp_line
			(start 0.670052 -1.100074)
			(end -0.670052 -1.100074)
			(stroke
				(width 0.1)
				(type default)
			)
			(layer "B.Fab")
		)
		(fp_line
			(start -0.670052 1.100074)
			(end 0.670052 1.100074)
			(stroke
				(width 0.1)
				(type default)
			)
			(layer "B.Fab")
		)
		(fp_line
			(start -0.670052 0.8001)
			(end -0.670052 1.100074)
			(stroke
				(width 0.1)
				(type default)
			)
			(layer "B.Fab")
		)
		(fp_line
			(start -0.670052 -0.8001)
			(end -0.670052 0.8001)
			(stroke
				(width 0.1)
				(type default)
			)
			(layer "B.Fab")
		)
		(fp_line
			(start -0.670052 -0.8001)
			(end -1.100074 -0.8001)
			(stroke
				(width 0.1)
				(type default)
			)
			(layer "B.Fab")
		)
		(fp_line
			(start -0.670052 -1.100074)
			(end -0.670052 -0.8001)
			(stroke
				(width 0.1)
				(type default)
			)
			(layer "B.Fab")
		)
		(fp_line
			(start -1.100074 0.8001)
			(end -0.670052 0.8001)
			(stroke
				(width 0.1)
				(type default)
			)
			(layer "B.Fab")
		)
		(fp_line
			(start -1.100074 -0.8001)
			(end -1.100074 0.8001)
			(stroke
				(width 0.1)
				(type default)
			)
			(layer "B.Fab")
		)
		(fp_poly
			(pts
				(xy 1.524 -0.649986) (xy 2.286 -1.030986) (xy 2.286 -0.268986)
			)
			(stroke
				(width 0)
				(type default)
			)
			(fill yes)
			(layer "B.Fab")
		)
		(pad "1" smd rect
			(at 0.94996 -0.649986 90)
			(size 0.4064 0.508)
			(layers "B.Cu" "B.Mask" "B.Paste")
			(net "BMC_MONITER_R")
		)
		(pad "2" smd rect
			(at 0.94996 0 90)
			(size 0.4064 0.508)
			(layers "B.Cu" "B.Mask" "B.Paste")
			(net "GND")
		)
		(pad "3" smd rect
			(at 0.94996 0.649986 90)
			(size 0.4064 0.508)
			(layers "B.Cu" "B.Mask" "B.Paste")
			(net "RST_SWB_BIC_R_N")
		)
		(pad "4" smd rect
			(at -0.94996 0.649986 90)
			(size 0.4064 0.508)
			(layers "B.Cu" "B.Mask" "B.Paste")
			(net "RST_SWB_BIC_BUF_R_N")
		)
		(pad "5" smd rect
			(at -0.94996 0 90)
			(size 0.4064 0.508)
			(layers "B.Cu" "B.Mask" "B.Paste")
			(net "P3V3_AUX")
		)
		(pad "6" smd rect
			(at -0.94996 -0.649986 90)
			(size 0.4064 0.508)
			(layers "B.Cu" "B.Mask" "B.Paste")
			(net "BMC_MONITER_BUF_R")
		)
	)
	(footprint ""
		(layer "B.Cu")
		(at 449.494402 -424.93311 180)
		(property "Reference" "PR6607"
			(at 0 0 0)
			(layer "B.SilkS")
			(hide yes)
			(effects
				(font
					(size 1.27 1.27)
				)
				(justify mirror)
			)
		)
		(property "Value" ""
			(at 0 0 0)
			(layer "B.Fab")
			(effects
				(font
					(size 1.27 1.27)
				)
				(justify mirror)
			)
		)
		(duplicate_pad_numbers_are_jumpers no)
		(fp_line
			(start 0.7874 0.4064)
			(end 0.7874 -0.4064)
			(stroke
				(width 0.1524)
				(type default)
			)
			(layer "B.SilkS")
		)
		(fp_line
			(start 0.7874 -0.4064)
			(end -0.7874 -0.4064)
			(stroke
				(width 0.1524)
				(type default)
			)
			(layer "B.SilkS")
		)
		(fp_line
			(start -0.7874 0.4064)
			(end 0.7874 0.4064)
			(stroke
				(width 0.1524)
				(type default)
			)
			(layer "B.SilkS")
		)
		(fp_line
			(start -0.7874 -0.4064)
			(end -0.7874 0.4064)
			(stroke
				(width 0.1524)
				(type default)
			)
			(layer "B.SilkS")
		)
		(fp_line
			(start 0.67945 0.3048)
			(end 0.67945 -0.305054)
			(stroke
				(width 0.1)
				(type default)
			)
			(layer "B.Fab")
		)
		(fp_line
			(start 0.67945 -0.305054)
			(end 0.12065 -0.305054)
			(stroke
				(width 0.1)
				(type default)
			)
			(layer "B.Fab")
		)
		(fp_line
			(start 0.12065 0.3048)
			(end 0.67945 0.3048)
			(stroke
				(width 0.1)
				(type default)
			)
			(layer "B.Fab")
		)
		(fp_line
			(start 0.12065 0.2794)
			(end 0.12065 0.3048)
			(stroke
				(width 0.1)
				(type default)
			)
			(layer "B.Fab")
		)
		(fp_line
			(start 0.12065 -0.2794)
			(end -0.12065 -0.2794)
			(stroke
				(width 0.1)
				(type default)
			)
			(layer "B.Fab")
		)
		(fp_line
			(start 0.12065 -0.305054)
			(end 0.12065 -0.2794)
			(stroke
				(width 0.1)
				(type default)
			)
			(layer "B.Fab")
		)
		(fp_line
			(start -0.120396 0.3048)
			(end -0.120396 0.2794)
			(stroke
				(width 0.1)
				(type default)
			)
			(layer "B.Fab")
		)
		(fp_line
			(start -0.120396 0.2794)
			(end 0.12065 0.2794)
			(stroke
				(width 0.1)
				(type default)
			)
			(layer "B.Fab")
		)
		(fp_line
			(start -0.12065 -0.2794)
			(end -0.12065 -0.3048)
			(stroke
				(width 0.1)
				(type default)
			)
			(layer "B.Fab")
		)
		(fp_line
			(start -0.12065 -0.3048)
			(end -0.67945 -0.3048)
			(stroke
				(width 0.1)
				(type default)
			)
			(layer "B.Fab")
		)
		(fp_line
			(start -0.67945 0.3048)
			(end -0.120396 0.3048)
			(stroke
				(width 0.1)
				(type default)
			)
			(layer "B.Fab")
		)
		(fp_line
			(start -0.67945 -0.3048)
			(end -0.67945 0.3048)
			(stroke
				(width 0.1)
				(type default)
			)
			(layer "B.Fab")
		)
		(pad "1" smd circle
			(at 0.40005 0)
			(size 0 0)
			(layers "B.Cu" "B.Mask" "B.Paste")
			(net "P0V9_RETIMER_CPU0_VINSEN")
		)
		(pad "2" smd circle
			(at -0.40005 0)
			(size 0 0)
			(layers "B.Cu" "B.Mask" "B.Paste")
			(net "GND")
		)
	)
)
